# TIMECARD (Time Appliance Project (Time Card)) — schematic netlist excerpt (pin names and nets, part order shuffled) for the footprints in the layout excerpt that follows; sources: Cadence DE-HDL packaged netlist, KiCad conversion of R4006-B0001-02_R01.brd

C142  CAPACITOR  0.1UF 10V 10%  pkg SMC_0402R_H022  page 14 : \1\ = XP2R5V_FPGA ; \2\ = SG
R30  RESISTOR  2.2KOHM 1%  pkg SMC_0402R_H016  page 32 : \1\ = XP5R0V_COMP ; \2\ = UNNAMED_516_CAPACITOR_I13_1

(kicad_pcb
	(version 20260206)
	(generator "pcbnew")
	(generator_version "10.0")
	(general
		(thickness 1.6)
		(legacy_teardrops no)
	)
	(paper "A4")
	(title_block
		(title "timecard-production-celestica-r4006 — R4006-B0001-02_R01.brd")
		(comment 1 "Time Appliance Project (Time Card) / footprints 1019-1020 of 1113")
	)
	(layers
		(0 "F.Cu" signal "TOP")
		(4 "In1.Cu" signal "L02_GND1")
		(6 "In2.Cu" signal "L03_SIG1")
		(8 "In3.Cu" signal "L04_GND2")
		(10 "In4.Cu" signal "L05_VCC1")
		(12 "In5.Cu" signal "L06_VCC2")
		(14 "In6.Cu" signal "L07_GND3")
		(16 "In7.Cu" signal "L08_SIG2")
		(18 "In8.Cu" signal "L09_GND4")
		(2 "B.Cu" signal "BOTTOM")
		(9 "F.Adhes" user "F.Adhesive")
		(11 "B.Adhes" user "B.Adhesive")
		(13 "F.Paste" user "Package Geometry/Pastemask Top")
		(15 "B.Paste" user "Package Geometry/Pastemask Bottom")
		(5 "F.SilkS" user "Ref Des/Silkscreen Top")
		(7 "B.SilkS" user "Ref Des/Silkscreen Bottom")
		(1 "F.Mask" user "Board Geometry/Soldermask Top")
		(3 "B.Mask" user "Board Geometry/Soldermask Bottom")
		(17 "Dwgs.User" user "User.Drawings")
		(19 "Cmts.User" user "User.Comments")
		(21 "Eco1.User" user "User.Eco1")
		(23 "Eco2.User" user "User.Eco2")
		(25 "Edge.Cuts" user "Board Geometry/Outline")
		(27 "Margin" user)
		(31 "F.CrtYd" user "Package Geometry/Place Bound Top")
		(29 "B.CrtYd" user "Package Geometry/Place Bound Bottom")
		(35 "F.Fab" user "Ref Des/Assembly Top")
		(33 "B.Fab" user "Ref Des/Assembly Bottom")
	)
	(footprint ""
		(layer "B.Cu")
		(at 109.4486 -37.211 -90)
		(property "Reference" "C142"
			(at 1.27 41.76395 270)
			(unlocked yes)
			(layer "B.SilkS")
			(effects
				(font
					(size 0.635 0.4064)
					(thickness 0.1524)
				)
				(justify mirror)
			)
		)
		(property "Value" "VAL*"
			(at 0 3.718306 270)
			(unlocked yes)
			(layer "B.Fab")
			(hide yes)
			(effects
				(font
					(size 0.7874 0.5842)
					(thickness 0.127)
				)
				(justify mirror)
			)
		)
		(property "Device Type" "CAPACITOR-G105-0B104-CK,0.1UF,A"
			(at 0 1.432306 270)
			(unlocked yes)
			(layer "B.Fab")
			(hide yes)
			(effects
				(font
					(size 0.7874 0.5842)
					(thickness 0.127)
				)
				(justify mirror)
			)
		)
		(property "User Part Number" "PARTNUM*"
			(at 0 2.575306 270)
			(unlocked yes)
			(layer "Cmts.User")
			(hide yes)
			(effects
				(font
					(size 0.7874 0.5842)
					(thickness 0.127)
				)
				(justify mirror)
			)
		)
		(property "Tolerance" "TOL*"
			(at 0 4.861306 270)
			(unlocked yes)
			(layer "Cmts.User")
			(hide yes)
			(effects
				(font
					(size 0.7874 0.5842)
					(thickness 0.127)
				)
				(justify mirror)
			)
		)
		(duplicate_pad_numbers_are_jumpers no)
		(fp_line
			(start -0.970026 0.4699)
			(end 0.970026 0.4699)
			(stroke
				(width 0.1)
				(type default)
			)
			(layer "B.SilkS")
		)
		(fp_line
			(start 0.970026 0.4699)
			(end 0.970026 -0.4699)
			(stroke
				(width 0.1)
				(type default)
			)
			(layer "B.SilkS")
		)
		(fp_line
			(start -0.970026 -0.4699)
			(end -0.970026 0.4699)
			(stroke
				(width 0.1)
				(type default)
			)
			(layer "B.SilkS")
		)
		(fp_line
			(start 0.970026 -0.4699)
			(end -0.970026 -0.4699)
			(stroke
				(width 0.1)
				(type default)
			)
			(layer "B.SilkS")
		)
		(fp_poly
			(pts
				(xy 0.970026 0.4699) (xy -0.970026 0.4699) (xy -0.970026 -0.4699) (xy 0.970026 -0.4699)
			)
			(stroke
				(width 0)
				(type default)
			)
			(fill no)
			(layer "B.CrtYd")
		)
		(fp_line
			(start -0.508 0.3048)
			(end 0.508 0.3048)
			(stroke
				(width 0.1)
				(type default)
			)
			(layer "B.Fab")
		)
		(fp_line
			(start 0.508 0.3048)
			(end 0.508 -0.3048)
			(stroke
				(width 0.1)
				(type default)
			)
			(layer "B.Fab")
		)
		(fp_line
			(start -0.508 -0.3048)
			(end -0.508 0.3048)
			(stroke
				(width 0.1)
				(type default)
			)
			(layer "B.Fab")
		)
		(fp_line
			(start 0.508 -0.3048)
			(end -0.508 -0.3048)
			(stroke
				(width 0.1)
				(type default)
			)
			(layer "B.Fab")
		)
		(pad "1" smd circle
			(at 0.500126 0 90)
			(size 0.635 0.635)
			(layers "B.Cu" "B.Mask" "B.Paste")
			(net "XP2R5V_FPGA")
		)
		(pad "2" smd circle
			(at -0.500126 0 90)
			(size 0.635 0.635)
			(layers "B.Cu" "B.Mask" "B.Paste")
			(net "SG")
		)
	)
	(footprint ""
		(layer "B.Cu")
		(at 36.9824 -101.3714)
		(property "Reference" "R30"
			(at -4.0386 0.64897 0)
			(unlocked yes)
			(layer "B.SilkS")
			(effects
				(font
					(size 0.7874 0.5842)
					(thickness 0.1524)
				)
				(justify mirror)
			)
		)
		(property "Value" "VAL*"
			(at -0.02032 2.13233 0)
			(unlocked yes)
			(layer "B.Fab")
			(hide yes)
			(effects
				(font
					(size 0.7874 0.5842)
					(thickness 0.1524)
				)
				(justify mirror)
			)
		)
		(property "Device Type" "RESISTOR-G155-12201-01,2.2KOHMA"
			(at -0.008382 1.210564 0)
			(unlocked yes)
			(layer "B.Fab")
			(hide yes)
			(effects
				(font
					(size 0.7874 0.5842)
					(thickness 0.1524)
				)
				(justify mirror)
			)
		)
		(property "User Part Number" "PARTNUM*"
			(at -0.02032 4.024884 0)
			(unlocked yes)
			(layer "Cmts.User")
			(hide yes)
			(effects
				(font
					(size 0.7874 0.5842)
					(thickness 0.1524)
				)
				(justify mirror)
			)
		)
		(property "Tolerance" "TOL*"
			(at -0.044704 3.05435 0)
			(unlocked yes)
			(layer "Cmts.User")
			(hide yes)
			(effects
				(font
					(size 0.7874 0.5842)
					(thickness 0.1524)
				)
				(justify mirror)
			)
		)
		(duplicate_pad_numbers_are_jumpers no)
		(fp_line
			(start -1.143 -0.5588)
			(end 1.143 -0.5588)
			(stroke
				(width 0.1)
				(type default)
			)
			(layer "B.SilkS")
		)
		(fp_line
			(start -1.143 0.5588)
			(end -1.143 -0.5588)
			(stroke
				(width 0.1)
				(type default)
			)
			(layer "B.SilkS")
		)
		(fp_line
			(start 1.143 -0.5588)
			(end 1.143 0.5588)
			(stroke
				(width 0.1)
				(type default)
			)
			(layer "B.SilkS")
		)
		(fp_line
			(start 1.143 0.5588)
			(end -1.143 0.5588)
			(stroke
				(width 0.1)
				(type default)
			)
			(layer "B.SilkS")
		)
		(fp_rect
			(start 1.143 -0.5588)
			(end -1.143 0.5588)
			(stroke
				(width 0)
				(type default)
			)
			(fill no)
			(layer "B.CrtYd")
		)
		(fp_line
			(start -0.508 -0.3048)
			(end 0.508 -0.3048)
			(stroke
				(width 0.1)
				(type default)
			)
			(layer "B.Fab")
		)
		(fp_line
			(start -0.508 0.3048)
			(end -0.508 -0.3048)
			(stroke
				(width 0.1)
				(type default)
			)
			(layer "B.Fab")
		)
		(fp_line
			(start 0.508 -0.3048)
			(end 0.508 0.3048)
			(stroke
				(width 0.1)
				(type default)
			)
			(layer "B.Fab")
		)
		(fp_line
			(start 0.508 0.3048)
			(end -0.508 0.3048)
			(stroke
				(width 0.1)
				(type default)
			)
			(layer "B.Fab")
		)
		(pad "1" smd rect
			(at 0.5334 0 180)
			(size 0.7112 0.6096)
			(layers "B.Cu" "B.Mask" "B.Paste")
			(net "XP5R0V_COMP")
		)
		(pad "2" smd rect
			(at -0.5334 0 180)
			(size 0.7112 0.6096)
			(layers "B.Cu" "B.Mask" "B.Paste")
			(net "UNNAMED_516_CAPACITOR_I13_1")
		)
		(zone
			(layer "B.Cu")
			(hatch none 0.5)
			(connect_pads
				(clearance 0)
			)
			(min_thickness 0.25)
			(keepout
				(tracks allowed)
				(vias not_allowed)
				(pads allowed)
				(copperpour not_allowed)
				(footprints allowed)
			)
			(placement
				(enabled no)
				(sheetname "")
			)
			(fill
				(thermal_gap 0.5)
				(thermal_bridge_width 0.5)
				(island_removal_mode 0)
			)
			(polygon
				(pts
					(xy 37.0586 -101.6762) (xy 36.9062 -101.6762) (xy 36.9062 -101.0666) (xy 37.0586 -101.0666)
				)
			)
		)
	)
)
